(kicad_pcb
	(version 20260206)
	(generator "pcbnew")
	(generator_version "10.0")
	(general
		(thickness 1.6)
		(legacy_teardrops no)
	)
	(paper "A4")
	(title_block
		(title "baseboard — 13948-1b.1110WZS1818.brd")
		(comment 1 "Honey Badger (Wiwynn) / footprints 1563-1569 of 2523")
	)
	(layers
		(0 "F.Cu" signal "TOP")
		(4 "In1.Cu" signal "L2GND")
		(6 "In2.Cu" signal "L3")
		(8 "In3.Cu" signal "L4VCC")
		(10 "In4.Cu" signal "L5VCC")
		(12 "In5.Cu" signal "L6")
		(14 "In6.Cu" signal "L7GND")
		(2 "B.Cu" signal "BOTTOM")
		(9 "F.Adhes" user "F.Adhesive")
		(11 "B.Adhes" user "B.Adhesive")
		(13 "F.Paste" user "Package Geometry/Pastemask Top")
		(15 "B.Paste" user "Package Geometry/Pastemask Bottom")
		(5 "F.SilkS" user "Ref Des/Silkscreen Top")
		(7 "B.SilkS" user "Ref Des/Silkscreen Bottom")
		(1 "F.Mask" user "Board Geometry/Soldermask Top")
		(3 "B.Mask" user "Board Geometry/Soldermask Bottom")
		(17 "Dwgs.User" user "User.Drawings")
		(19 "Cmts.User" user "User.Comments")
		(21 "Eco1.User" user "User.Eco1")
		(23 "Eco2.User" user "User.Eco2")
		(25 "Edge.Cuts" user "Board Geometry/Outline")
		(27 "Margin" user)
		(31 "F.CrtYd" user "Package Geometry/Place Bound Top")
		(29 "B.CrtYd" user "Package Geometry/Place Bound Bottom")
		(35 "F.Fab" user "Ref Des/Assembly Top")
		(33 "B.Fab" user "Ref Des/Assembly Bottom")
	)
	(footprint ""
		(layer "F.Cu")
		(at 81.031842 -116.784882 -90)
		(property "Reference" "SR756"
			(at 0 0 270)
			(layer "F.SilkS")
			(hide yes)
			(effects
				(font
					(size 1.27 1.27)
				)
			)
		)
		(property "Value" "4K7R2F-GP"
			(at 0.064008 -3.993896 270)
			(unlocked yes)
			(layer "F.Fab")
			(hide yes)
			(effects
				(font
					(size 1.016 1.016)
					(thickness 0.1524)
				)
			)
		)
		(property "Device Type" "R402H16"
			(at 0.064008 -5.517896 270)
			(unlocked yes)
			(layer "F.Fab")
			(hide yes)
			(effects
				(font
					(size 1.016 1.016)
					(thickness 0.1524)
				)
			)
		)
		(duplicate_pad_numbers_are_jumpers no)
		(fp_line
			(start -0.508 -0.9398)
			(end -0.508 0.9398)
			(stroke
				(width 0.1524)
				(type default)
			)
			(layer "F.SilkS")
		)
		(fp_line
			(start 0.508 -0.9398)
			(end -0.508 -0.9398)
			(stroke
				(width 0.1524)
				(type default)
			)
			(layer "F.SilkS")
		)
		(fp_rect
			(start -0.508 0.9398)
			(end 0.508 -0.9398)
			(stroke
				(width 0)
				(type default)
			)
			(fill no)
			(layer "F.CrtYd")
		)
		(fp_rect
			(start -0.508 0.9398)
			(end 0.508 -0.9398)
			(stroke
				(width 0)
				(type default)
			)
			(fill no)
			(layer "F.Fab")
		)
		(pad "1" smd custom
			(at 0 -0.4445 270)
			(size 0.1397 0.1397)
			(layers "F.Cu" "F.Mask" "F.Paste")
			(net "EXP_IOC_BMC_SCL_14")
			(options
				(clearance outline)
				(anchor circle)
			)
			(primitives
				(gr_poly
					(pts
						(arc
							(start -0.1778 -0.2794)
							(mid -0.249642 -0.249642)
							(end -0.2794 -0.1778)
						)
						(arc
							(start -0.2794 0.1778)
							(mid -0.249642 0.249642)
							(end -0.1778 0.2794)
						)
						(arc
							(start 0.1778 0.2794)
							(mid 0.249642 0.249642)
							(end 0.2794 0.1778)
						)
						(arc
							(start 0.2794 -0.1778)
							(mid 0.249642 -0.249642)
							(end 0.1778 -0.2794)
						)
					)
					(width 0)
					(fill yes)
				)
			)
		)
		(pad "2" smd custom
			(at 0 0.4445 270)
			(size 0.1397 0.1397)
			(layers "F.Cu" "F.Mask" "F.Paste")
			(net "P3V3_STBY")
			(options
				(clearance outline)
				(anchor circle)
			)
			(primitives
				(gr_poly
					(pts
						(arc
							(start -0.1778 -0.2794)
							(mid -0.249642 -0.249642)
							(end -0.2794 -0.1778)
						)
						(arc
							(start -0.2794 0.1778)
							(mid -0.249642 0.249642)
							(end -0.1778 0.2794)
						)
						(arc
							(start 0.1778 0.2794)
							(mid 0.249642 0.249642)
							(end 0.2794 0.1778)
						)
						(arc
							(start 0.2794 -0.1778)
							(mid 0.249642 -0.249642)
							(end 0.1778 -0.2794)
						)
					)
					(width 0)
					(fill yes)
				)
			)
		)
	)
	(footprint ""
		(layer "F.Cu")
		(at 57.912 -211.074)
		(property "Reference" "PR9005"
			(at 0 0 0)
			(layer "F.SilkS")
			(hide yes)
			(effects
				(font
					(size 1.27 1.27)
				)
			)
		)
		(property "Value" "0R2J-2-GP"
			(at 0.064008 -3.993896 0)
			(unlocked yes)
			(layer "F.Fab")
			(hide yes)
			(effects
				(font
					(size 1.016 1.016)
					(thickness 0.1524)
				)
			)
		)
		(property "Device Type" "R402H16"
			(at 0.064008 -5.517896 0)
			(unlocked yes)
			(layer "F.Fab")
			(hide yes)
			(effects
				(font
					(size 1.016 1.016)
					(thickness 0.1524)
				)
			)
		)
		(duplicate_pad_numbers_are_jumpers no)
		(fp_line
			(start -0.508 -0.9398)
			(end -0.508 0.9398)
			(stroke
				(width 0.1524)
				(type default)
			)
			(layer "F.SilkS")
		)
		(fp_line
			(start 0.508 -0.9398)
			(end -0.508 -0.9398)
			(stroke
				(width 0.1524)
				(type default)
			)
			(layer "F.SilkS")
		)
		(fp_rect
			(start -0.508 0.9398)
			(end 0.508 -0.9398)
			(stroke
				(width 0)
				(type default)
			)
			(fill no)
			(layer "F.CrtYd")
		)
		(fp_rect
			(start -0.508 0.9398)
			(end 0.508 -0.9398)
			(stroke
				(width 0)
				(type default)
			)
			(fill no)
			(layer "F.Fab")
		)
		(pad "1" smd custom
			(at 0 -0.4445)
			(size 0.1397 0.1397)
			(layers "F.Cu" "F.Mask" "F.Paste")
			(net "HSW_SCL_2")
			(options
				(clearance outline)
				(anchor circle)
			)
			(primitives
				(gr_poly
					(pts
						(arc
							(start -0.1778 -0.2794)
							(mid -0.249642 -0.249642)
							(end -0.2794 -0.1778)
						)
						(arc
							(start -0.2794 0.1778)
							(mid -0.249642 0.249642)
							(end -0.1778 0.2794)
						)
						(arc
							(start 0.1778 0.2794)
							(mid 0.249642 0.249642)
							(end 0.2794 0.1778)
						)
						(arc
							(start 0.2794 -0.1778)
							(mid 0.249642 -0.249642)
							(end 0.1778 -0.2794)
						)
					)
					(width 0)
					(fill yes)
				)
			)
		)
		(pad "2" smd custom
			(at 0 0.4445)
			(size 0.1397 0.1397)
			(layers "F.Cu" "F.Mask" "F.Paste")
			(net "BMC_I2C_SCL_10")
			(options
				(clearance outline)
				(anchor circle)
			)
			(primitives
				(gr_poly
					(pts
						(arc
							(start -0.1778 -0.2794)
							(mid -0.249642 -0.249642)
							(end -0.2794 -0.1778)
						)
						(arc
							(start -0.2794 0.1778)
							(mid -0.249642 0.249642)
							(end -0.1778 0.2794)
						)
						(arc
							(start 0.1778 0.2794)
							(mid 0.249642 0.249642)
							(end 0.2794 0.1778)
						)
						(arc
							(start 0.2794 -0.1778)
							(mid 0.249642 -0.249642)
							(end 0.1778 -0.2794)
						)
					)
					(width 0)
					(fill yes)
				)
			)
		)
	)
	(footprint ""
		(layer "F.Cu")
		(at 344.17 -107.188 180)
		(property "Reference" "PR12"
			(at 0 0 180)
			(layer "F.SilkS")
			(hide yes)
			(effects
				(font
					(size 1.27 1.27)
				)
			)
		)
		(property "Value" "0R2J-2-GP"
			(at 0.064008 -3.993896 180)
			(unlocked yes)
			(layer "F.Fab")
			(hide yes)
			(effects
				(font
					(size 1.016 1.016)
					(thickness 0.1524)
				)
			)
		)
		(property "Device Type" "R402H16"
			(at 0.064008 -5.517896 180)
			(unlocked yes)
			(layer "F.Fab")
			(hide yes)
			(effects
				(font
					(size 1.016 1.016)
					(thickness 0.1524)
				)
			)
		)
		(duplicate_pad_numbers_are_jumpers no)
		(fp_line
			(start 0.508 -0.9398)
			(end -0.508 -0.9398)
			(stroke
				(width 0.1524)
				(type default)
			)
			(layer "F.SilkS")
		)
		(fp_line
			(start -0.508 -0.9398)
			(end -0.508 0.9398)
			(stroke
				(width 0.1524)
				(type default)
			)
			(layer "F.SilkS")
		)
		(fp_rect
			(start -0.508 0.9398)
			(end 0.508 -0.9398)
			(stroke
				(width 0)
				(type default)
			)
			(fill no)
			(layer "F.CrtYd")
		)
		(fp_rect
			(start -0.508 0.9398)
			(end 0.508 -0.9398)
			(stroke
				(width 0)
				(type default)
			)
			(fill no)
			(layer "F.Fab")
		)
		(pad "1" smd custom
			(at 0 -0.4445 180)
			(size 0.1397 0.1397)
			(layers "F.Cu" "F.Mask" "F.Paste")
			(net "P5V_STBY_VBST_RR")
			(options
				(clearance outline)
				(anchor circle)
			)
			(primitives
				(gr_poly
					(pts
						(arc
							(start -0.1778 -0.2794)
							(mid -0.249642 -0.249642)
							(end -0.2794 -0.1778)
						)
						(arc
							(start -0.2794 0.1778)
							(mid -0.249642 0.249642)
							(end -0.1778 0.2794)
						)
						(arc
							(start 0.1778 0.2794)
							(mid 0.249642 0.249642)
							(end 0.2794 0.1778)
						)
						(arc
							(start 0.2794 -0.1778)
							(mid 0.249642 -0.249642)
							(end 0.1778 -0.2794)
						)
					)
					(width 0)
					(fill yes)
				)
			)
		)
		(pad "2" smd custom
			(at 0 0.4445 180)
			(size 0.1397 0.1397)
			(layers "F.Cu" "F.Mask" "F.Paste")
			(net "P5V_STBY_VBST")
			(options
				(clearance outline)
				(anchor circle)
			)
			(primitives
				(gr_poly
					(pts
						(arc
							(start -0.1778 -0.2794)
							(mid -0.249642 -0.249642)
							(end -0.2794 -0.1778)
						)
						(arc
							(start -0.2794 0.1778)
							(mid -0.249642 0.249642)
							(end -0.1778 0.2794)
						)
						(arc
							(start 0.1778 0.2794)
							(mid 0.249642 0.249642)
							(end 0.2794 0.1778)
						)
						(arc
							(start 0.2794 -0.1778)
							(mid 0.249642 -0.249642)
							(end 0.1778 -0.2794)
						)
					)
					(width 0)
					(fill yes)
				)
			)
		)
	)
	(footprint ""
		(layer "F.Cu")
		(at 273.549872 -50.999136 -90)
		(property "Reference" "PR119"
			(at 0 0 270)
			(layer "F.SilkS")
			(hide yes)
			(effects
				(font
					(size 1.27 1.27)
				)
			)
		)
		(property "Value" "10KR2F-2-GP"
			(at 0.064008 -3.993896 270)
			(unlocked yes)
			(layer "F.Fab")
			(hide yes)
			(effects
				(font
					(size 1.016 1.016)
					(thickness 0.1524)
				)
			)
		)
		(property "Device Type" "R402H16"
			(at 0.064008 -5.517896 270)
			(unlocked yes)
			(layer "F.Fab")
			(hide yes)
			(effects
				(font
					(size 1.016 1.016)
					(thickness 0.1524)
				)
			)
		)
		(duplicate_pad_numbers_are_jumpers no)
		(fp_line
			(start -0.508 -0.9398)
			(end -0.508 0.9398)
			(stroke
				(width 0.1524)
				(type default)
			)
			(layer "F.SilkS")
		)
		(fp_line
			(start 0.508 -0.9398)
			(end -0.508 -0.9398)
			(stroke
				(width 0.1524)
				(type default)
			)
			(layer "F.SilkS")
		)
		(fp_rect
			(start -0.508 0.9398)
			(end 0.508 -0.9398)
			(stroke
				(width 0)
				(type default)
			)
			(fill no)
			(layer "F.CrtYd")
		)
		(fp_rect
			(start -0.508 0.9398)
			(end 0.508 -0.9398)
			(stroke
				(width 0)
				(type default)
			)
			(fill no)
			(layer "F.Fab")
		)
		(pad "1" smd custom
			(at 0 -0.4445 270)
			(size 0.1397 0.1397)
			(layers "F.Cu" "F.Mask" "F.Paste")
			(net "P12V")
			(options
				(clearance outline)
				(anchor circle)
			)
			(primitives
				(gr_poly
					(pts
						(arc
							(start -0.1778 -0.2794)
							(mid -0.249642 -0.249642)
							(end -0.2794 -0.1778)
						)
						(arc
							(start -0.2794 0.1778)
							(mid -0.249642 0.249642)
							(end -0.1778 0.2794)
						)
						(arc
							(start 0.1778 0.2794)
							(mid 0.249642 0.249642)
							(end 0.2794 0.1778)
						)
						(arc
							(start 0.2794 -0.1778)
							(mid 0.249642 -0.249642)
							(end 0.1778 -0.2794)
						)
					)
					(width 0)
					(fill yes)
				)
			)
		)
		(pad "2" smd custom
			(at 0 0.4445 270)
			(size 0.1397 0.1397)
			(layers "F.Cu" "F.Mask" "F.Paste")
			(net "P3V3_S_LV")
			(options
				(clearance outline)
				(anchor circle)
			)
			(primitives
				(gr_poly
					(pts
						(arc
							(start -0.1778 -0.2794)
							(mid -0.249642 -0.249642)
							(end -0.2794 -0.1778)
						)
						(arc
							(start -0.2794 0.1778)
							(mid -0.249642 0.249642)
							(end -0.1778 0.2794)
						)
						(arc
							(start 0.1778 0.2794)
							(mid 0.249642 0.249642)
							(end 0.2794 0.1778)
						)
						(arc
							(start 0.2794 -0.1778)
							(mid 0.249642 -0.249642)
							(end 0.1778 -0.2794)
						)
					)
					(width 0)
					(fill yes)
				)
			)
		)
	)
	(footprint ""
		(layer "F.Cu")
		(at 113.792 -26.924 -90)
		(property "Reference" "SR664"
			(at 0 0 270)
			(layer "F.SilkS")
			(hide yes)
			(effects
				(font
					(size 1.27 1.27)
				)
			)
		)
		(property "Value" "10KR2F-2-GP"
			(at 0.064008 -3.993896 270)
			(unlocked yes)
			(layer "F.Fab")
			(hide yes)
			(effects
				(font
					(size 1.016 1.016)
					(thickness 0.1524)
				)
			)
		)
		(property "Device Type" "R402H16"
			(at 0.064008 -5.517896 270)
			(unlocked yes)
			(layer "F.Fab")
			(hide yes)
			(effects
				(font
					(size 1.016 1.016)
					(thickness 0.1524)
				)
			)
		)
		(duplicate_pad_numbers_are_jumpers no)
		(fp_line
			(start -0.508 -0.9398)
			(end -0.508 0.9398)
			(stroke
				(width 0.1524)
				(type default)
			)
			(layer "F.SilkS")
		)
		(fp_line
			(start 0.508 -0.9398)
			(end -0.508 -0.9398)
			(stroke
				(width 0.1524)
				(type default)
			)
			(layer "F.SilkS")
		)
		(fp_rect
			(start -0.508 0.9398)
			(end 0.508 -0.9398)
			(stroke
				(width 0)
				(type default)
			)
			(fill no)
			(layer "F.CrtYd")
		)
		(fp_rect
			(start -0.508 0.9398)
			(end 0.508 -0.9398)
			(stroke
				(width 0)
				(type default)
			)
			(fill no)
			(layer "F.Fab")
		)
		(pad "1" smd custom
			(at 0 -0.4445 270)
			(size 0.1397 0.1397)
			(layers "F.Cu" "F.Mask" "F.Paste")
			(net "P1V8_C")
			(options
				(clearance outline)
				(anchor circle)
			)
			(primitives
				(gr_poly
					(pts
						(arc
							(start -0.1778 -0.2794)
							(mid -0.249642 -0.249642)
							(end -0.2794 -0.1778)
						)
						(arc
							(start -0.2794 0.1778)
							(mid -0.249642 0.249642)
							(end -0.1778 0.2794)
						)
						(arc
							(start 0.1778 0.2794)
							(mid 0.249642 0.249642)
							(end 0.2794 0.1778)
						)
						(arc
							(start 0.2794 -0.1778)
							(mid 0.249642 -0.249642)
							(end 0.1778 -0.2794)
						)
					)
					(width 0)
					(fill yes)
				)
			)
		)
		(pad "2" smd custom
			(at 0 0.4445 270)
			(size 0.1397 0.1397)
			(layers "F.Cu" "F.Mask" "F.Paste")
			(net "SYS_DBMODE1")
			(options
				(clearance outline)
				(anchor circle)
			)
			(primitives
				(gr_poly
					(pts
						(arc
							(start -0.1778 -0.2794)
							(mid -0.249642 -0.249642)
							(end -0.2794 -0.1778)
						)
						(arc
							(start -0.2794 0.1778)
							(mid -0.249642 0.249642)
							(end -0.1778 0.2794)
						)
						(arc
							(start 0.1778 0.2794)
							(mid 0.249642 0.249642)
							(end 0.2794 0.1778)
						)
						(arc
							(start 0.2794 -0.1778)
							(mid 0.249642 -0.249642)
							(end 0.1778 -0.2794)
						)
					)
					(width 0)
					(fill yes)
				)
			)
		)
	)
	(footprint ""
		(layer "F.Cu")
		(at 306.578 -193.802 180)
		(property "Reference" "R170"
			(at 0 0 180)
			(layer "F.SilkS")
			(hide yes)
			(effects
				(font
					(size 1.27 1.27)
				)
			)
		)
		(property "Value" "100KR2F-L1-GP"
			(at 0.064008 -3.993896 180)
			(unlocked yes)
			(layer "F.Fab")
			(hide yes)
			(effects
				(font
					(size 1.016 1.016)
					(thickness 0.1524)
				)
			)
		)
		(property "Device Type" "R402H16"
			(at 0.064008 -5.517896 180)
			(unlocked yes)
			(layer "F.Fab")
			(hide yes)
			(effects
				(font
					(size 1.016 1.016)
					(thickness 0.1524)
				)
			)
		)
		(duplicate_pad_numbers_are_jumpers no)
		(fp_line
			(start 0.508 -0.9398)
			(end -0.508 -0.9398)
			(stroke
				(width 0.1524)
				(type default)
			)
			(layer "F.SilkS")
		)
		(fp_line
			(start -0.508 -0.9398)
			(end -0.508 0.9398)
			(stroke
				(width 0.1524)
				(type default)
			)
			(layer "F.SilkS")
		)
		(fp_rect
			(start -0.508 0.9398)
			(end 0.508 -0.9398)
			(stroke
				(width 0)
				(type default)
			)
			(fill no)
			(layer "F.CrtYd")
		)
		(fp_rect
			(start -0.508 0.9398)
			(end 0.508 -0.9398)
			(stroke
				(width 0)
				(type default)
			)
			(fill no)
			(layer "F.Fab")
		)
		(pad "1" smd custom
			(at 0 -0.4445 180)
			(size 0.1397 0.1397)
			(layers "F.Cu" "F.Mask" "F.Paste")
			(net "P3V3_STBY")
			(options
				(clearance outline)
				(anchor circle)
			)
			(primitives
				(gr_poly
					(pts
						(arc
							(start -0.1778 -0.2794)
							(mid -0.249642 -0.249642)
							(end -0.2794 -0.1778)
						)
						(arc
							(start -0.2794 0.1778)
							(mid -0.249642 0.249642)
							(end -0.1778 0.2794)
						)
						(arc
							(start 0.1778 0.2794)
							(mid 0.249642 0.249642)
							(end 0.2794 0.1778)
						)
						(arc
							(start 0.2794 -0.1778)
							(mid 0.249642 -0.249642)
							(end 0.1778 -0.2794)
						)
					)
					(width 0)
					(fill yes)
				)
			)
		)
		(pad "2" smd custom
			(at 0 0.4445 180)
			(size 0.1397 0.1397)
			(layers "F.Cu" "F.Mask" "F.Paste")
			(net "LED_DR_LED0")
			(options
				(clearance outline)
				(anchor circle)
			)
			(primitives
				(gr_poly
					(pts
						(arc
							(start -0.1778 -0.2794)
							(mid -0.249642 -0.249642)
							(end -0.2794 -0.1778)
						)
						(arc
							(start -0.2794 0.1778)
							(mid -0.249642 0.249642)
							(end -0.1778 0.2794)
						)
						(arc
							(start 0.1778 0.2794)
							(mid 0.249642 0.249642)
							(end 0.2794 0.1778)
						)
						(arc
							(start 0.2794 -0.1778)
							(mid 0.249642 -0.249642)
							(end 0.1778 -0.2794)
						)
					)
					(width 0)
					(fill yes)
				)
			)
		)
	)
	(footprint ""
		(layer "F.Cu")
		(at 84.709 -240.8174 180)
		(property "Reference" "SC436"
			(at 0 0 180)
			(layer "F.SilkS")
			(hide yes)
			(effects
				(font
					(size 1.27 1.27)
				)
			)
		)
		(property "Value" "SCD1U16V2KX-3GP"
			(at 1.1811 -2.7051 180)
			(unlocked yes)
			(layer "F.Fab")
			(hide yes)
			(effects
				(font
					(size 1.016 1.016)
					(thickness 0.1524)
				)
			)
		)
		(property "Device Type" "C402H22"
			(at 1.1811 -4.2291 180)
			(unlocked yes)
			(layer "F.Fab")
			(hide yes)
			(effects
				(font
					(size 1.016 1.016)
					(thickness 0.1524)
				)
			)
		)
		(duplicate_pad_numbers_are_jumpers no)
		(fp_rect
			(start -0.4318 0.9525)
			(end 0.4318 -0.9525)
			(stroke
				(width 0)
				(type default)
			)
			(fill no)
			(layer "F.CrtYd")
		)
		(fp_rect
			(start -0.4318 0.9525)
			(end 0.4318 -0.9525)
			(stroke
				(width 0)
				(type default)
			)
			(fill no)
			(layer "F.Fab")
		)
		(pad "1" smd custom
			(at 0 -0.4445 180)
			(size 0.1524 0.1524)
			(layers "F.Cu" "F.Mask" "F.Paste")
			(net "P3V3_STBY")
			(options
				(clearance outline)
				(anchor circle)
			)
			(primitives
				(gr_poly
					(pts
						(arc
							(start 0.3048 -0.2032)
							(mid 0.275042 -0.275042)
							(end 0.2032 -0.3048)
						)
						(arc
							(start -0.2032 -0.3048)
							(mid -0.275042 -0.275042)
							(end -0.3048 -0.2032)
						)
						(arc
							(start -0.3048 0.2032)
							(mid -0.275042 0.275042)
							(end -0.2032 0.3048)
						)
						(arc
							(start 0.2032 0.3048)
							(mid 0.275042 0.275042)
							(end 0.3048 0.2032)
						)
					)
					(width 0)
					(fill yes)
				)
			)
		)
		(pad "2" smd custom
			(at 0 0.4445 180)
			(size 0.1524 0.1524)
			(layers "F.Cu" "F.Mask" "F.Paste")
			(net "GND")
			(options
				(clearance outline)
				(anchor circle)
			)
			(primitives
				(gr_poly
					(pts
						(arc
							(start 0.3048 -0.2032)
							(mid 0.275042 -0.275042)
							(end 0.2032 -0.3048)
						)
						(arc
							(start -0.2032 -0.3048)
							(mid -0.275042 -0.275042)
							(end -0.3048 -0.2032)
						)
						(arc
							(start -0.3048 0.2032)
							(mid -0.275042 0.275042)
							(end -0.2032 0.3048)
						)
						(arc
							(start 0.2032 0.3048)
							(mid 0.275042 0.275042)
							(end 0.3048 0.2032)
						)
					)
					(width 0)
					(fill yes)
				)
			)
		)
	)
)
